FILE_TYPE = MACRO_DRAWING;
SET COLOR_WIRE YELLOW;
SET COLOR_PROP ORANGE;
SET COLOR_DOT WHITE;
SET COLOR_ARC YELLOW;
SET COLOR_BODY GREEN;
SET COLOR_NOTE PURPLE;
SET PROP_DISPLAY VALUE;
SET PAGE_NUMBER P2;
FORCEADD QUANTA_TITLE_BLOCK_C..2
(-100 100);
FORCEPROP 1 LAST Q_TITLE TABLE OF CONTENT 1/3
J 0
(-9416 151);
DISPLAY 2.446809 (-9416 151);
PAINT GREEN (-9416 151);
FORCEPROP 1 LAST CUSTOM_TXT_CDS <CON_TC_SNM78>
J 0
(-5200 1975);
FORCEPROP 1 LAST CUSTOM_TXT_CDS <CON_TC_SNM77>
J 0
(-5200 2075);
FORCEPROP 1 LAST CUSTOM_TXT_CDS <CON_TC_SNO74>
J 2
(-5300 2375);
FORCEPROP 1 LAST CUSTOM_TXT_CDS <CON_TC_SNO75>
J 2
(-5300 2275);
FORCEPROP 1 LAST CUSTOM_TXT_CDS <CON_TC_SNO77>
J 2
(-5300 2075);
FORCEPROP 1 LAST CUSTOM_TXT_CDS <CON_TC_SNM119>
J 0
(-2700 1875);
FORCEPROP 1 LAST CUSTOM_TXT_CDS <CON_TC_SNO115>
J 2
(-2800 2275);
FORCEPROP 1 LAST CUSTOM_TXT_CDS <CON_TC_SNM63>
J 0
(-5200 3475);
FORCEPROP 1 LAST CUSTOM_TXT_CDS <CON_TC_SNM8>
J 0
(-7700 4975);
FORCEPROP 1 LAST CUSTOM_TXT_CDS <CON_TC_SNM57>
J 0
(-5200 4075);
FORCEPROP 1 LAST CUSTOM_TXT_CDS <CON_TC_SNO82>
J 2
(-2800 5575);
FORCEPROP 1 LAST CUSTOM_TXT_CDS <CON_TC_SNM37>
J 0
(-7700 2075);
FORCEPROP 1 LAST CUSTOM_TXT_CDS <CON_TC_SNM36>
J 0
(-7700 2175);
FORCEPROP 1 LAST CUSTOM_TXT_CDS <CON_TC_SNM35>
J 0
(-7700 2275);
FORCEPROP 1 LAST CUSTOM_TXT_CDS <CON_TC_SNM40>
J 0
(-7700 1775);
FORCEPROP 1 LAST CUSTOM_TXT_CDS <Q_REV>
J 0
(-275 200);
DISPLAY 1.212766 (-275 200);
FORCEPROP 1 LAST CUSTOM_TXT_CDS <CON_PAGE_NUM> OF <CON_TOTAL_PAGES>
J 0
(-538 113);
DISPLAY 0.978723 (-538 113);
FORCEPROP 1 LAST CUSTOM_TXT_CDS <CON_LAST_MODIFIED>
J 0
(-2000 125);
DISPLAY 0.978723 (-2000 125);
FORCEPROP 1 LAST CUSTOM_TXT_CDS <Q_NUMBER>
J 0
(-1500 200);
DISPLAY 1.212766 (-1500 200);
FORCEPROP 1 LAST CUSTOM_TXT_CDS <Q_PROJ>
J 0
(-2475 200);
DISPLAY 1.212766 (-2475 200);
FORCEPROP 1 LAST CUSTOM_TXT_CDS <CON_TC_SNM1>
J 0
(-7700 5675);
FORCEPROP 1 LAST CUSTOM_TXT_CDS <CON_TC_SNM2>
J 0
(-7700 5575);
FORCEPROP 1 LAST CUSTOM_TXT_CDS <CON_TC_SNM3>
J 0
(-7700 5475);
FORCEPROP 1 LAST CUSTOM_TXT_CDS <CON_TC_SNM4>
J 0
(-7700 5375);
FORCEPROP 1 LAST CUSTOM_TXT_CDS <CON_TC_SNM5>
J 0
(-7700 5275);
FORCEPROP 1 LAST CUSTOM_TXT_CDS <CON_TC_SNM6>
J 0
(-7700 5175);
FORCEPROP 1 LAST CUSTOM_TXT_CDS <CON_TC_SNM7>
J 0
(-7700 5075);
FORCEPROP 1 LAST CUSTOM_TXT_CDS <CON_TC_SNM9>
J 0
(-7700 4875);
FORCEPROP 1 LAST CUSTOM_TXT_CDS <CON_TC_SNM10>
J 0
(-7700 4775);
FORCEPROP 1 LAST CUSTOM_TXT_CDS <CON_TC_SNM11>
J 0
(-7700 4675);
FORCEPROP 1 LAST CUSTOM_TXT_CDS <CON_TC_SNM12>
J 0
(-7700 4575);
FORCEPROP 1 LAST CUSTOM_TXT_CDS <CON_TC_SNM13>
J 0
(-7700 4475);
FORCEPROP 1 LAST CUSTOM_TXT_CDS <CON_TC_SNM14>
J 0
(-7700 4375);
FORCEPROP 1 LAST CUSTOM_TXT_CDS <CON_TC_SNM15>
J 0
(-7700 4275);
FORCEPROP 1 LAST CUSTOM_TXT_CDS <CON_TC_SNM16>
J 0
(-7700 4175);
FORCEPROP 1 LAST CUSTOM_TXT_CDS <CON_TC_SNM17>
J 0
(-7700 4075);
FORCEPROP 1 LAST CUSTOM_TXT_CDS <CON_TC_SNM18>
J 0
(-7700 3975);
FORCEPROP 1 LAST CUSTOM_TXT_CDS <CON_TC_SNM19>
J 0
(-7700 3875);
FORCEPROP 1 LAST CUSTOM_TXT_CDS <CON_TC_SNM20>
J 0
(-7700 3775);
FORCEPROP 1 LAST CUSTOM_TXT_CDS <CON_TC_SNM21>
J 0
(-7700 3675);
FORCEPROP 1 LAST CUSTOM_TXT_CDS <CON_TC_SNM22>
J 0
(-7700 3575);
FORCEPROP 1 LAST CUSTOM_TXT_CDS <CON_TC_SNM23>
J 0
(-7700 3475);
FORCEPROP 1 LAST CUSTOM_TXT_CDS <CON_TC_SNM24>
J 0
(-7700 3375);
FORCEPROP 1 LAST CUSTOM_TXT_CDS <CON_TC_SNM25>
J 0
(-7700 3275);
FORCEPROP 1 LAST CUSTOM_TXT_CDS <CON_TC_SNM26>
J 0
(-7700 3175);
FORCEPROP 1 LAST CUSTOM_TXT_CDS <CON_TC_SNM27>
J 0
(-7700 3075);
FORCEPROP 1 LAST CUSTOM_TXT_CDS <CON_TC_SNM28>
J 0
(-7700 2975);
FORCEPROP 1 LAST CUSTOM_TXT_CDS <CON_TC_SNM29>
J 0
(-7700 2875);
FORCEPROP 1 LAST CUSTOM_TXT_CDS <CON_TC_SNM38>
J 0
(-7700 1975);
FORCEPROP 1 LAST CUSTOM_TXT_CDS <CON_TC_SNM39>
J 0
(-7700 1875);
FORCEPROP 1 LAST CUSTOM_TXT_CDS <CON_TC_SNM41>
J 0
(-5200 5675);
FORCEPROP 1 LAST CUSTOM_TXT_CDS <CON_TC_SNM42>
J 0
(-5200 5575);
FORCEPROP 1 LAST CUSTOM_TXT_CDS <CON_TC_SNM43>
J 0
(-5200 5475);
FORCEPROP 1 LAST CUSTOM_TXT_CDS <CON_TC_SNM44>
J 0
(-5200 5375);
FORCEPROP 1 LAST CUSTOM_TXT_CDS <CON_TC_SNM45>
J 0
(-5200 5275);
FORCEPROP 1 LAST CUSTOM_TXT_CDS <CON_TC_SNM46>
J 0
(-5200 5175);
FORCEPROP 1 LAST CUSTOM_TXT_CDS <CON_TC_SNM47>
J 0
(-5200 5075);
FORCEPROP 1 LAST CUSTOM_TXT_CDS <CON_TC_SNM48>
J 0
(-5200 4975);
FORCEPROP 1 LAST CUSTOM_TXT_CDS <CON_TC_SNM49>
J 0
(-5200 4875);
FORCEPROP 1 LAST CUSTOM_TXT_CDS <CON_TC_SNM50>
J 0
(-5200 4775);
FORCEPROP 1 LAST CUSTOM_TXT_CDS <CON_TC_SNM51>
J 0
(-5200 4675);
FORCEPROP 1 LAST CUSTOM_TXT_CDS <CON_TC_SNM52>
J 0
(-5200 4575);
FORCEPROP 1 LAST CUSTOM_TXT_CDS <CON_TC_SNM53>
J 0
(-5200 4475);
FORCEPROP 1 LAST CUSTOM_TXT_CDS <CON_TC_SNM54>
J 0
(-5200 4375);
FORCEPROP 1 LAST CUSTOM_TXT_CDS <CON_TC_SNM55>
J 0
(-5200 4275);
FORCEPROP 1 LAST CUSTOM_TXT_CDS <CON_TC_SNM56>
J 0
(-5200 4175);
FORCEPROP 1 LAST CUSTOM_TXT_CDS <CON_TC_SNM58>
J 0
(-5200 3975);
FORCEPROP 1 LAST CUSTOM_TXT_CDS <CON_TC_SNM59>
J 0
(-5200 3875);
FORCEPROP 1 LAST CUSTOM_TXT_CDS <CON_TC_SNM60>
J 0
(-5200 3775);
FORCEPROP 1 LAST CUSTOM_TXT_CDS <CON_TC_SNM61>
J 0
(-5200 3675);
FORCEPROP 1 LAST CUSTOM_TXT_CDS <CON_TC_SNM62>
J 0
(-5200 3575);
FORCEPROP 1 LAST CUSTOM_TXT_CDS <CON_TC_SNM64>
J 0
(-5200 3375);
FORCEPROP 1 LAST CUSTOM_TXT_CDS <CON_TC_SNM65>
J 0
(-5200 3275);
FORCEPROP 1 LAST CUSTOM_TXT_CDS <CON_TC_SNM66>
J 0
(-5200 3175);
FORCEPROP 1 LAST CUSTOM_TXT_CDS <CON_TC_SNM67>
J 0
(-5200 3075);
FORCEPROP 1 LAST CUSTOM_TXT_CDS <CON_TC_SNM68>
J 0
(-5200 2975);
FORCEPROP 1 LAST CUSTOM_TXT_CDS <CON_TC_SNM69>
J 0
(-5200 2875);
FORCEPROP 1 LAST CUSTOM_TXT_CDS <CON_TC_SNM70>
J 0
(-5200 2775);
FORCEPROP 1 LAST CUSTOM_TXT_CDS <CON_TC_SNM71>
J 0
(-5200 2675);
FORCEPROP 1 LAST CUSTOM_TXT_CDS <CON_TC_SNM72>
J 0
(-5200 2575);
FORCEPROP 1 LAST CUSTOM_TXT_CDS <CON_TC_SNM73>
J 0
(-5200 2475);
FORCEPROP 1 LAST CUSTOM_TXT_CDS <CON_TC_SNM81>
J 0
(-2700 5675);
FORCEPROP 1 LAST CUSTOM_TXT_CDS <CON_TC_SNM82>
J 0
(-2700 5575);
FORCEPROP 1 LAST CUSTOM_TXT_CDS <CON_TC_SNM83>
J 0
(-2700 5475);
FORCEPROP 1 LAST CUSTOM_TXT_CDS <CON_TC_SNM84>
J 0
(-2700 5375);
FORCEPROP 1 LAST CUSTOM_TXT_CDS <CON_TC_SNM85>
J 0
(-2700 5275);
FORCEPROP 1 LAST CUSTOM_TXT_CDS <CON_TC_SNM86>
J 0
(-2700 5175);
FORCEPROP 1 LAST CUSTOM_TXT_CDS <CON_TC_SNM87>
J 0
(-2700 5075);
FORCEPROP 1 LAST CUSTOM_TXT_CDS <CON_TC_SNM88>
J 0
(-2700 4975);
FORCEPROP 1 LAST CUSTOM_TXT_CDS <CON_TC_SNM89>
J 0
(-2700 4875);
FORCEPROP 1 LAST CUSTOM_TXT_CDS <CON_TC_SNM90>
J 0
(-2700 4775);
FORCEPROP 1 LAST CUSTOM_TXT_CDS <CON_TC_SNM91>
J 0
(-2700 4675);
FORCEPROP 1 LAST CUSTOM_TXT_CDS <CON_TC_SNM92>
J 0
(-2700 4575);
FORCEPROP 1 LAST CUSTOM_TXT_CDS <CON_TC_SNM93>
J 0
(-2700 4475);
FORCEPROP 1 LAST CUSTOM_TXT_CDS <CON_TC_SNM94>
J 0
(-2700 4375);
FORCEPROP 1 LAST CUSTOM_TXT_CDS <CON_TC_SNM95>
J 0
(-2700 4275);
FORCEPROP 1 LAST CUSTOM_TXT_CDS <CON_TC_SNM96>
J 0
(-2700 4175);
FORCEPROP 1 LAST CUSTOM_TXT_CDS <CON_TC_SNM97>
J 0
(-2700 4075);
FORCEPROP 1 LAST CUSTOM_TXT_CDS <CON_TC_SNM98>
J 0
(-2700 3975);
FORCEPROP 1 LAST CUSTOM_TXT_CDS <CON_TC_SNM99>
J 0
(-2700 3875);
FORCEPROP 1 LAST CUSTOM_TXT_CDS <CON_TC_SNM100>
J 0
(-2700 3775);
FORCEPROP 1 LAST CUSTOM_TXT_CDS <CON_TC_SNM101>
J 0
(-2700 3675);
FORCEPROP 1 LAST CUSTOM_TXT_CDS <CON_TC_SNM102>
J 0
(-2700 3575);
FORCEPROP 1 LAST CUSTOM_TXT_CDS <CON_TC_SNM103>
J 0
(-2700 3475);
FORCEPROP 1 LAST CUSTOM_TXT_CDS <CON_TC_SNM104>
J 0
(-2700 3375);
FORCEPROP 1 LAST CUSTOM_TXT_CDS <CON_TC_SNM105>
J 0
(-2700 3275);
FORCEPROP 1 LAST CUSTOM_TXT_CDS <CON_TC_SNM106>
J 0
(-2700 3175);
FORCEPROP 1 LAST CUSTOM_TXT_CDS <CON_TC_SNM107>
J 0
(-2700 3075);
FORCEPROP 1 LAST CUSTOM_TXT_CDS <CON_TC_SNM108>
J 0
(-2700 2975);
FORCEPROP 1 LAST CUSTOM_TXT_CDS <CON_TC_SNM109>
J 0
(-2700 2875);
FORCEPROP 1 LAST CUSTOM_TXT_CDS <CON_TC_SNM110>
J 0
(-2700 2775);
FORCEPROP 1 LAST CUSTOM_TXT_CDS <CON_TC_SNM111>
J 0
(-2700 2675);
FORCEPROP 1 LAST CUSTOM_TXT_CDS <CON_TC_SNM112>
J 0
(-2700 2575);
FORCEPROP 1 LAST CUSTOM_TXT_CDS <CON_TC_SNM113>
J 0
(-2700 2475);
FORCEPROP 1 LAST CUSTOM_TXT_CDS <CON_TC_SNM114>
J 0
(-2700 2375);
FORCEPROP 1 LAST CUSTOM_TXT_CDS <CON_TC_SNM115>
J 0
(-2700 2275);
FORCEPROP 1 LAST CUSTOM_TXT_CDS <CON_TC_SNM116>
J 0
(-2700 2175);
FORCEPROP 1 LAST CUSTOM_TXT_CDS <CON_TC_SNM117>
J 0
(-2700 2075);
FORCEPROP 1 LAST CUSTOM_TXT_CDS <CON_TC_SNM118>
J 0
(-2700 1975);
FORCEPROP 1 LAST CUSTOM_TXT_CDS <CON_TC_SNM120>
J 0
(-2700 1775);
FORCEPROP 1 LAST CUSTOM_TXT_CDS <CON_TC_SNO1>
J 2
(-7800 5675);
FORCEPROP 1 LAST CUSTOM_TXT_CDS <CON_TC_SNO2>
J 2
(-7800 5575);
FORCEPROP 1 LAST CUSTOM_TXT_CDS <CON_TC_SNO3>
J 2
(-7800 5475);
FORCEPROP 1 LAST CUSTOM_TXT_CDS <CON_TC_SNO4>
J 2
(-7800 5375);
FORCEPROP 1 LAST CUSTOM_TXT_CDS <CON_TC_SNO5>
J 2
(-7800 5275);
FORCEPROP 1 LAST CUSTOM_TXT_CDS <CON_TC_SNO6>
J 2
(-7800 5175);
FORCEPROP 1 LAST CUSTOM_TXT_CDS <CON_TC_SNO7>
J 2
(-7800 5075);
FORCEPROP 1 LAST CUSTOM_TXT_CDS <CON_TC_SNO8>
J 2
(-7800 4975);
FORCEPROP 1 LAST CUSTOM_TXT_CDS <CON_TC_SNO9>
J 2
(-7800 4875);
FORCEPROP 1 LAST CUSTOM_TXT_CDS <CON_TC_SNO10>
J 2
(-7800 4775);
FORCEPROP 1 LAST CUSTOM_TXT_CDS <CON_TC_SNO11>
J 2
(-7800 4675);
FORCEPROP 1 LAST CUSTOM_TXT_CDS <CON_TC_SNO12>
J 2
(-7800 4575);
FORCEPROP 1 LAST CUSTOM_TXT_CDS <CON_TC_SNO13>
J 2
(-7800 4475);
FORCEPROP 1 LAST CUSTOM_TXT_CDS <CON_TC_SNO14>
J 2
(-7800 4375);
FORCEPROP 1 LAST CUSTOM_TXT_CDS <CON_TC_SNO15>
J 2
(-7800 4275);
FORCEPROP 1 LAST CUSTOM_TXT_CDS <CON_TC_SNO16>
J 2
(-7800 4175);
FORCEPROP 1 LAST CUSTOM_TXT_CDS <CON_TC_SNO17>
J 2
(-7800 4075);
FORCEPROP 1 LAST CUSTOM_TXT_CDS <CON_TC_SNO18>
J 2
(-7800 3975);
FORCEPROP 1 LAST CUSTOM_TXT_CDS <CON_TC_SNO19>
J 2
(-7800 3875);
FORCEPROP 1 LAST CUSTOM_TXT_CDS <CON_TC_SNO20>
J 2
(-7800 3775);
FORCEPROP 1 LAST CUSTOM_TXT_CDS <CON_TC_SNO21>
J 2
(-7800 3675);
FORCEPROP 1 LAST CUSTOM_TXT_CDS <CON_TC_SNO22>
J 2
(-7800 3575);
FORCEPROP 1 LAST CUSTOM_TXT_CDS <CON_TC_SNO23>
J 2
(-7800 3475);
FORCEPROP 1 LAST CUSTOM_TXT_CDS <CON_TC_SNO24>
J 2
(-7800 3375);
FORCEPROP 1 LAST CUSTOM_TXT_CDS <CON_TC_SNO25>
J 2
(-7800 3275);
FORCEPROP 1 LAST CUSTOM_TXT_CDS <CON_TC_SNO26>
J 2
(-7800 3175);
FORCEPROP 1 LAST CUSTOM_TXT_CDS <CON_TC_SNO27>
J 2
(-7800 3075);
FORCEPROP 1 LAST CUSTOM_TXT_CDS <CON_TC_SNO28>
J 2
(-7800 2975);
FORCEPROP 1 LAST CUSTOM_TXT_CDS <CON_TC_SNO30>
J 2
(-7800 2775);
FORCEPROP 1 LAST CUSTOM_TXT_CDS <CON_TC_SNO31>
J 2
(-7800 2675);
FORCEPROP 1 LAST CUSTOM_TXT_CDS <CON_TC_SNO32>
J 2
(-7800 2575);
FORCEPROP 1 LAST CUSTOM_TXT_CDS <CON_TC_SNO33>
J 2
(-7800 2475);
FORCEPROP 1 LAST CUSTOM_TXT_CDS <CON_TC_SNO34>
J 2
(-7800 2375);
FORCEPROP 1 LAST CUSTOM_TXT_CDS <CON_TC_SNO35>
J 2
(-7800 2275);
FORCEPROP 1 LAST CUSTOM_TXT_CDS <CON_TC_SNO36>
J 2
(-7800 2175);
FORCEPROP 1 LAST CUSTOM_TXT_CDS <CON_TC_SNO37>
J 2
(-7800 2075);
FORCEPROP 1 LAST CUSTOM_TXT_CDS <CON_TC_SNO38>
J 2
(-7800 1975);
FORCEPROP 1 LAST CUSTOM_TXT_CDS <CON_TC_SNO39>
J 2
(-7800 1875);
FORCEPROP 1 LAST CUSTOM_TXT_CDS <CON_TC_SNO40>
J 2
(-7800 1775);
FORCEPROP 1 LAST CUSTOM_TXT_CDS <CON_TC_SNO41>
J 2
(-5300 5675);
FORCEPROP 1 LAST CUSTOM_TXT_CDS <CON_TC_SNO42>
J 2
(-5300 5575);
FORCEPROP 1 LAST CUSTOM_TXT_CDS <CON_TC_SNO43>
J 2
(-5300 5475);
FORCEPROP 1 LAST CUSTOM_TXT_CDS <CON_TC_SNO44>
J 2
(-5300 5375);
FORCEPROP 1 LAST CUSTOM_TXT_CDS <CON_TC_SNO45>
J 2
(-5300 5275);
FORCEPROP 1 LAST CUSTOM_TXT_CDS <CON_TC_SNO46>
J 2
(-5300 5175);
FORCEPROP 1 LAST CUSTOM_TXT_CDS <CON_TC_SNO47>
J 2
(-5300 5075);
FORCEPROP 1 LAST CUSTOM_TXT_CDS <CON_TC_SNO48>
J 2
(-5300 4975);
FORCEPROP 1 LAST CUSTOM_TXT_CDS <CON_TC_SNO49>
J 2
(-5300 4875);
FORCEPROP 1 LAST CUSTOM_TXT_CDS <CON_TC_SNO50>
J 2
(-5300 4775);
FORCEPROP 1 LAST CUSTOM_TXT_CDS <CON_TC_SNO51>
J 2
(-5300 4675);
FORCEPROP 1 LAST CUSTOM_TXT_CDS <CON_TC_SNO52>
J 2
(-5300 4575);
FORCEPROP 1 LAST CUSTOM_TXT_CDS <CON_TC_SNO53>
J 2
(-5300 4475);
FORCEPROP 1 LAST CUSTOM_TXT_CDS <CON_TC_SNO54>
J 2
(-5300 4375);
FORCEPROP 1 LAST CUSTOM_TXT_CDS <CON_TC_SNO55>
J 2
(-5300 4275);
FORCEPROP 1 LAST CUSTOM_TXT_CDS <CON_TC_SNO56>
J 2
(-5300 4175);
FORCEPROP 1 LAST CUSTOM_TXT_CDS <CON_TC_SNO57>
J 2
(-5300 4075);
FORCEPROP 1 LAST CUSTOM_TXT_CDS <CON_TC_SNO58>
J 2
(-5300 3975);
FORCEPROP 1 LAST CUSTOM_TXT_CDS <CON_TC_SNO59>
J 2
(-5300 3875);
FORCEPROP 1 LAST CUSTOM_TXT_CDS <CON_TC_SNO60>
J 2
(-5300 3775);
FORCEPROP 1 LAST CUSTOM_TXT_CDS <CON_TC_SNO61>
J 2
(-5300 3675);
FORCEPROP 1 LAST CUSTOM_TXT_CDS <CON_TC_SNO62>
J 2
(-5300 3575);
FORCEPROP 1 LAST CUSTOM_TXT_CDS <CON_TC_SNO63>
J 2
(-5300 3475);
FORCEPROP 1 LAST CUSTOM_TXT_CDS <CON_TC_SNO64>
J 2
(-5300 3375);
FORCEPROP 1 LAST CUSTOM_TXT_CDS <CON_TC_SNO65>
J 2
(-5300 3275);
FORCEPROP 1 LAST CUSTOM_TXT_CDS <CON_TC_SNO66>
J 2
(-5300 3175);
FORCEPROP 1 LAST CUSTOM_TXT_CDS <CON_TC_SNO67>
J 2
(-5300 3075);
FORCEPROP 1 LAST CUSTOM_TXT_CDS <CON_TC_SNO68>
J 2
(-5300 2975);
FORCEPROP 1 LAST CUSTOM_TXT_CDS <CON_TC_SNO69>
J 2
(-5300 2875);
FORCEPROP 1 LAST CUSTOM_TXT_CDS <CON_TC_SNO70>
J 2
(-5300 2775);
FORCEPROP 1 LAST CUSTOM_TXT_CDS <CON_TC_SNO71>
J 2
(-5300 2675);
FORCEPROP 1 LAST CUSTOM_TXT_CDS <CON_TC_SNO72>
J 2
(-5300 2575);
FORCEPROP 1 LAST CUSTOM_TXT_CDS <CON_TC_SNO73>
J 2
(-5300 2475);
FORCEPROP 1 LAST CUSTOM_TXT_CDS <CON_TC_SNO76>
J 2
(-5300 2175);
FORCEPROP 1 LAST CUSTOM_TXT_CDS <CON_TC_SNO80>
J 2
(-5300 1775);
FORCEPROP 1 LAST CUSTOM_TXT_CDS <CON_TC_SNO81>
J 2
(-2800 5675);
FORCEPROP 1 LAST CUSTOM_TXT_CDS <CON_TC_SNO83>
J 2
(-2800 5475);
FORCEPROP 1 LAST CUSTOM_TXT_CDS <CON_TC_SNO84>
J 2
(-2800 5375);
FORCEPROP 1 LAST CUSTOM_TXT_CDS <CON_TC_SNO85>
J 2
(-2800 5275);
FORCEPROP 1 LAST CUSTOM_TXT_CDS <CON_TC_SNO86>
J 2
(-2800 5175);
FORCEPROP 1 LAST CUSTOM_TXT_CDS <CON_TC_SNO87>
J 2
(-2800 5075);
FORCEPROP 1 LAST CUSTOM_TXT_CDS <CON_TC_SNO88>
J 2
(-2800 4975);
FORCEPROP 1 LAST CUSTOM_TXT_CDS <CON_TC_SNO89>
J 2
(-2800 4875);
FORCEPROP 1 LAST CUSTOM_TXT_CDS <CON_TC_SNO90>
J 2
(-2800 4775);
FORCEPROP 1 LAST CUSTOM_TXT_CDS <CON_TC_SNO91>
J 2
(-2800 4675);
FORCEPROP 1 LAST CUSTOM_TXT_CDS <CON_TC_SNO92>
J 2
(-2800 4575);
FORCEPROP 1 LAST CUSTOM_TXT_CDS <CON_TC_SNO93>
J 2
(-2800 4475);
FORCEPROP 1 LAST CUSTOM_TXT_CDS <CON_TC_SNO94>
J 2
(-2800 4375);
FORCEPROP 1 LAST CUSTOM_TXT_CDS <CON_TC_SNO95>
J 2
(-2800 4275);
FORCEPROP 1 LAST CUSTOM_TXT_CDS <CON_TC_SNO96>
J 2
(-2800 4175);
FORCEPROP 1 LAST CUSTOM_TXT_CDS <CON_TC_SNO97>
J 2
(-2800 4075);
FORCEPROP 1 LAST CUSTOM_TXT_CDS <CON_TC_SNO98>
J 2
(-2800 3975);
FORCEPROP 1 LAST CUSTOM_TXT_CDS <CON_TC_SNO99>
J 2
(-2800 3875);
FORCEPROP 1 LAST CUSTOM_TXT_CDS <CON_TC_SNO100>
J 2
(-2800 3775);
FORCEPROP 1 LAST CUSTOM_TXT_CDS <CON_TC_SNO101>
J 2
(-2800 3675);
FORCEPROP 1 LAST CUSTOM_TXT_CDS <CON_TC_SNO102>
J 2
(-2800 3575);
FORCEPROP 1 LAST CUSTOM_TXT_CDS <CON_TC_SNO103>
J 2
(-2800 3475);
FORCEPROP 1 LAST CUSTOM_TXT_CDS <CON_TC_SNO104>
J 2
(-2800 3375);
FORCEPROP 1 LAST CUSTOM_TXT_CDS <CON_TC_SNO105>
J 2
(-2800 3275);
FORCEPROP 1 LAST CUSTOM_TXT_CDS <CON_TC_SNO106>
J 2
(-2800 3175);
FORCEPROP 1 LAST CUSTOM_TXT_CDS <CON_TC_SNO107>
J 2
(-2800 3075);
FORCEPROP 1 LAST CUSTOM_TXT_CDS <CON_TC_SNO108>
J 2
(-2800 2975);
FORCEPROP 1 LAST CUSTOM_TXT_CDS <CON_TC_SNO109>
J 2
(-2800 2875);
FORCEPROP 1 LAST CUSTOM_TXT_CDS <CON_TC_SNO110>
J 2
(-2800 2775);
FORCEPROP 1 LAST CUSTOM_TXT_CDS <CON_TC_SNO111>
J 2
(-2800 2675);
FORCEPROP 1 LAST CUSTOM_TXT_CDS <CON_TC_SNO112>
J 2
(-2800 2575);
FORCEPROP 1 LAST CUSTOM_TXT_CDS <CON_TC_SNO113>
J 2
(-2800 2475);
FORCEPROP 1 LAST CUSTOM_TXT_CDS <CON_TC_SNO114>
J 2
(-2800 2375);
FORCEPROP 1 LAST CUSTOM_TXT_CDS <CON_TC_SNO116>
J 2
(-2800 2175);
FORCEPROP 1 LAST CUSTOM_TXT_CDS <CON_TC_SNO117>
J 2
(-2800 2075);
FORCEPROP 1 LAST CUSTOM_TXT_CDS <CON_TC_SNO118>
J 2
(-2800 1975);
FORCEPROP 1 LAST CUSTOM_TXT_CDS <CON_TC_SNO119>
J 2
(-2800 1875);
FORCEPROP 1 LAST CUSTOM_TXT_CDS <CON_TC_SNO120>
J 2
(-2800 1775);
FORCEPROP 1 LAST CUSTOM_TXT_CDS <CON_TC_SNO29>
J 2
(-7800 2875);
FORCEPROP 1 LAST CUSTOM_TXT_CDS <CON_TC_SNM30>
J 0
(-7700 2775);
FORCEPROP 1 LAST CUSTOM_TXT_CDS <CON_TC_SNM31>
J 0
(-7700 2675);
FORCEPROP 1 LAST CUSTOM_TXT_CDS <CON_TC_SNM32>
J 0
(-7700 2575);
FORCEPROP 1 LAST CUSTOM_TXT_CDS <CON_TC_SNM33>
J 0
(-7700 2475);
FORCEPROP 1 LAST CUSTOM_TXT_CDS <CON_TC_SNM34>
J 0
(-7700 2375);
FORCEPROP 2 LAST CUSTOM_TXT_CDS <NAME_2>
J 0
(-3325 150);
DISPLAY 1.021277 (-3325 150);
FORCEPROP 2 LAST CUSTOM_TXT_CDS <NAME_1>
J 0
(-3325 275);
DISPLAY 1.021277 (-3325 275);
FORCEPROP 1 LAST Q_DEPT BU9
J 1
(-3851 149);
DISPLAY 1.957447 (-3851 149);
PAINT GREEN (-3851 149);
FORCEPROP 1 LAST CUSTOM_TXT_CDS <CON_TC_SNM79>
J 0
(-5200 1875);
FORCEPROP 1 LAST CUSTOM_TXT_CDS <CON_TC_SNM74>
J 0
(-5200 2375);
FORCEPROP 1 LAST CUSTOM_TXT_CDS <CON_TC_SNM75>
J 0
(-5200 2275);
FORCEPROP 1 LAST CUSTOM_TXT_CDS <CON_TC_SNM76>
J 0
(-5200 2175);
FORCEPROP 1 LAST CUSTOM_TXT_CDS <CON_TC_SNM80>
J 0
(-5200 1775);
FORCEPROP 1 LAST CUSTOM_TXT_CDS <CON_TC_SNO79>
J 2
(-5300 1875);
FORCEPROP 1 LAST CUSTOM_TXT_CDS <CON_TC_SNO78>
J 2
(-5300 1975);
FORCEPROP 2 LAST CDS_LIB pure_quanta
J 0
(-100 100);
DISPLAY INVISIBLE (-100 100);
FORCEPROP 2 LAST PAGE_BORDER TRUE
J 0
(-7990 5350);
DISPLAY 0.638298 (-7990 5350);
PAINT PINK (-7990 5350);
DISPLAY INVISIBLE (-7990 5350);
FORCEPROP 1 LAST TOC_SYMBOL TRUE
J 0
(-9274 6552);
DISPLAY 0.978723 (-9274 6552);
PAINT GREEN (-9274 6552);
DISPLAY INVISIBLE (-9274 6552);
FORCEPROP 1 LAST COMMENT_BODY TRUE
J 0
(-1249 126);
DISPLAY 0.978723 (-1249 126);
PAINT GREEN (-1249 126);
DISPLAY INVISIBLE (-1249 126);
FORCEPROP 0 LAST CDS_CON_LAST_MODIFIED Mon Nov 15 20:05:01 2021
J 0
(-2000 125);
DISPLAY INVISIBLE (-2000 125);
FORCEPROP 2 LAST CUSTOM_TXT_CDS <XR_PAGE_TITLE>
J 0
(-7990 5350);
DISPLAY 0.638298 (-7990 5350);
PAINT PINK (-7990 5350);
DISPLAY INVISIBLE (-7990 5350);
FORCEPROP 2 LAST CDS_XR_PAGE_TITLE CR-2 : @T6G_MB_LIB.T6G(SCH_1):PAGE2
J 0
(-7990 5350);
DISPLAY 0.638298 (-7990 5350);
PAINT PINK (-7990 5350);
DISPLAY INVISIBLE (-7990 5350);
QUIT
